# S9S_MB_2U (Grand Teton) — schematic netlist excerpt (pin names and nets, part order shuffled) for the footprints in the layout excerpt that follows; sources: Cadence DE-HDL packaged netlist, KiCad conversion of 03242023_DA0F0TMBIJ0_F0T_Motherboard_J_brd_V01_OCP.brd

R1139  Q_RES  0 5% CHIP  pkg 0402LF  page 155 : A = CLK_50M_RMII ; B = CLK_50M_RMII_R
R928  Q_RES  10K 1% CHIP  pkg 0402LF  page 221 : A = P3V3_AUX ; B = JTAG_BMC_PLD_TDO

(kicad_pcb
	(version 20260206)
	(generator "pcbnew")
	(generator_version "10.0")
	(general
		(thickness 1.6)
		(legacy_teardrops no)
	)
	(paper "A4")
	(title_block
		(title "03242023_DA0F0TMBIJ0_F0T_Motherboard_J_brd_V01_OCP.brd")
		(comment 1 "Grand Teton / footprints 3334-3335 of 6105")
	)
	(layers
		(0 "F.Cu" signal "TOP")
		(4 "In1.Cu" signal "GND")
		(6 "In2.Cu" signal "IN1")
		(8 "In3.Cu" signal "GND1")
		(10 "In4.Cu" signal "IN2")
		(12 "In5.Cu" signal "GND2")
		(14 "In6.Cu" signal "IN3")
		(16 "In7.Cu" signal "GND3")
		(18 "In8.Cu" signal "VCC")
		(20 "In9.Cu" signal "VCC1")
		(22 "In10.Cu" signal "GND4")
		(24 "In11.Cu" signal "IN4")
		(26 "In12.Cu" signal "GND5")
		(28 "In13.Cu" signal "IN5")
		(30 "In14.Cu" signal "GND6")
		(32 "In15.Cu" signal "IN6")
		(34 "In16.Cu" signal "GND7")
		(2 "B.Cu" signal "BOTTOM")
		(9 "F.Adhes" user "F.Adhesive")
		(11 "B.Adhes" user "B.Adhesive")
		(13 "F.Paste" user "Package Geometry/Pastemask Top")
		(15 "B.Paste" user "Package Geometry/Pastemask Bottom")
		(5 "F.SilkS" user "Ref Des/Silkscreen Top")
		(7 "B.SilkS" user "Ref Des/Silkscreen Bottom")
		(1 "F.Mask" user "Board Geometry/Soldermask Top")
		(3 "B.Mask" user "Board Geometry/Soldermask Bottom")
		(17 "Dwgs.User" user "User.Drawings")
		(19 "Cmts.User" user "User.Comments")
		(21 "Eco1.User" user "User.Eco1")
		(23 "Eco2.User" user "User.Eco2")
		(25 "Edge.Cuts" user "Board Geometry/Outline")
		(27 "Margin" user)
		(31 "F.CrtYd" user "Package Geometry/Place Bound Top")
		(29 "B.CrtYd" user "Package Geometry/Place Bound Bottom")
		(35 "F.Fab" user "Ref Des/Assembly Top")
		(33 "B.Fab" user "Ref Des/Assembly Bottom")
	)
	(footprint ""
		(layer "F.Cu")
		(at 215.90381 -23.304754 -90)
		(property "Reference" "R1139"
			(at 0 0 270)
			(layer "F.SilkS")
			(hide yes)
			(effects
				(font
					(size 1.27 1.27)
				)
			)
		)
		(property "Value" ""
			(at 0 0 270)
			(layer "F.Fab")
			(effects
				(font
					(size 1.27 1.27)
				)
			)
		)
		(duplicate_pad_numbers_are_jumpers no)
		(fp_line
			(start -0.7874 0.4064)
			(end -0.7874 -0.4064)
			(stroke
				(width 0.1524)
				(type default)
			)
			(layer "F.SilkS")
		)
		(fp_line
			(start 0.7874 0.4064)
			(end -0.7874 0.4064)
			(stroke
				(width 0.1524)
				(type default)
			)
			(layer "F.SilkS")
		)
		(fp_line
			(start -0.7874 -0.4064)
			(end 0.7874 -0.4064)
			(stroke
				(width 0.1524)
				(type default)
			)
			(layer "F.SilkS")
		)
		(fp_line
			(start 0.7874 -0.4064)
			(end 0.7874 0.4064)
			(stroke
				(width 0.1524)
				(type default)
			)
			(layer "F.SilkS")
		)
		(fp_line
			(start -0.67945 0.3048)
			(end -0.67945 -0.305054)
			(stroke
				(width 0.1)
				(type default)
			)
			(layer "F.Fab")
		)
		(fp_line
			(start -0.12065 0.3048)
			(end -0.67945 0.3048)
			(stroke
				(width 0.1)
				(type default)
			)
			(layer "F.Fab")
		)
		(fp_line
			(start 0.120396 0.3048)
			(end 0.120396 0.2794)
			(stroke
				(width 0.1)
				(type default)
			)
			(layer "F.Fab")
		)
		(fp_line
			(start 0.67945 0.3048)
			(end 0.120396 0.3048)
			(stroke
				(width 0.1)
				(type default)
			)
			(layer "F.Fab")
		)
		(fp_line
			(start -0.12065 0.2794)
			(end -0.12065 0.3048)
			(stroke
				(width 0.1)
				(type default)
			)
			(layer "F.Fab")
		)
		(fp_line
			(start 0.120396 0.2794)
			(end -0.12065 0.2794)
			(stroke
				(width 0.1)
				(type default)
			)
			(layer "F.Fab")
		)
		(fp_line
			(start -0.12065 -0.2794)
			(end 0.12065 -0.2794)
			(stroke
				(width 0.1)
				(type default)
			)
			(layer "F.Fab")
		)
		(fp_line
			(start 0.12065 -0.2794)
			(end 0.12065 -0.3048)
			(stroke
				(width 0.1)
				(type default)
			)
			(layer "F.Fab")
		)
		(fp_line
			(start 0.12065 -0.3048)
			(end 0.67945 -0.3048)
			(stroke
				(width 0.1)
				(type default)
			)
			(layer "F.Fab")
		)
		(fp_line
			(start 0.67945 -0.3048)
			(end 0.67945 0.3048)
			(stroke
				(width 0.1)
				(type default)
			)
			(layer "F.Fab")
		)
		(fp_line
			(start -0.67945 -0.305054)
			(end -0.12065 -0.305054)
			(stroke
				(width 0.1)
				(type default)
			)
			(layer "F.Fab")
		)
		(fp_line
			(start -0.12065 -0.305054)
			(end -0.12065 -0.2794)
			(stroke
				(width 0.1)
				(type default)
			)
			(layer "F.Fab")
		)
		(pad "1" smd circle
			(at -0.40005 0 270)
			(size 0 0)
			(layers "F.Cu" "F.Mask" "F.Paste")
			(net "CLK_50M_RMII")
		)
		(pad "2" smd circle
			(at 0.40005 0 270)
			(size 0 0)
			(layers "F.Cu" "F.Mask" "F.Paste")
			(net "CLK_50M_RMII_R")
		)
	)
	(footprint ""
		(layer "F.Cu")
		(at 129.411984 -66.938906 90)
		(property "Reference" "R928"
			(at 0 0 90)
			(layer "F.SilkS")
			(hide yes)
			(effects
				(font
					(size 1.27 1.27)
				)
			)
		)
		(property "Value" ""
			(at 0 0 90)
			(layer "F.Fab")
			(effects
				(font
					(size 1.27 1.27)
				)
			)
		)
		(duplicate_pad_numbers_are_jumpers no)
		(fp_line
			(start 0.7874 -0.4064)
			(end 0.7874 0.4064)
			(stroke
				(width 0.1524)
				(type default)
			)
			(layer "F.SilkS")
		)
		(fp_line
			(start -0.7874 -0.4064)
			(end 0.7874 -0.4064)
			(stroke
				(width 0.1524)
				(type default)
			)
			(layer "F.SilkS")
		)
		(fp_line
			(start 0.7874 0.4064)
			(end -0.7874 0.4064)
			(stroke
				(width 0.1524)
				(type default)
			)
			(layer "F.SilkS")
		)
		(fp_line
			(start -0.7874 0.4064)
			(end -0.7874 -0.4064)
			(stroke
				(width 0.1524)
				(type default)
			)
			(layer "F.SilkS")
		)
		(fp_line
			(start -0.12065 -0.305054)
			(end -0.12065 -0.2794)
			(stroke
				(width 0.1)
				(type default)
			)
			(layer "F.Fab")
		)
		(fp_line
			(start -0.67945 -0.305054)
			(end -0.12065 -0.305054)
			(stroke
				(width 0.1)
				(type default)
			)
			(layer "F.Fab")
		)
		(fp_line
			(start 0.67945 -0.3048)
			(end 0.67945 0.3048)
			(stroke
				(width 0.1)
				(type default)
			)
			(layer "F.Fab")
		)
		(fp_line
			(start 0.12065 -0.3048)
			(end 0.67945 -0.3048)
			(stroke
				(width 0.1)
				(type default)
			)
			(layer "F.Fab")
		)
		(fp_line
			(start 0.12065 -0.2794)
			(end 0.12065 -0.3048)
			(stroke
				(width 0.1)
				(type default)
			)
			(layer "F.Fab")
		)
		(fp_line
			(start -0.12065 -0.2794)
			(end 0.12065 -0.2794)
			(stroke
				(width 0.1)
				(type default)
			)
			(layer "F.Fab")
		)
		(fp_line
			(start 0.120396 0.2794)
			(end -0.12065 0.2794)
			(stroke
				(width 0.1)
				(type default)
			)
			(layer "F.Fab")
		)
		(fp_line
			(start -0.12065 0.2794)
			(end -0.12065 0.3048)
			(stroke
				(width 0.1)
				(type default)
			)
			(layer "F.Fab")
		)
		(fp_line
			(start 0.67945 0.3048)
			(end 0.120396 0.3048)
			(stroke
				(width 0.1)
				(type default)
			)
			(layer "F.Fab")
		)
		(fp_line
			(start 0.120396 0.3048)
			(end 0.120396 0.2794)
			(stroke
				(width 0.1)
				(type default)
			)
			(layer "F.Fab")
		)
		(fp_line
			(start -0.12065 0.3048)
			(end -0.67945 0.3048)
			(stroke
				(width 0.1)
				(type default)
			)
			(layer "F.Fab")
		)
		(fp_line
			(start -0.67945 0.3048)
			(end -0.67945 -0.305054)
			(stroke
				(width 0.1)
				(type default)
			)
			(layer "F.Fab")
		)
		(pad "1" smd circle
			(at -0.40005 0 90)
			(size 0 0)
			(layers "F.Cu" "F.Mask" "F.Paste")
			(net "P3V3_AUX")
		)
		(pad "2" smd circle
			(at 0.40005 0 90)
			(size 0 0)
			(layers "F.Cu" "F.Mask" "F.Paste")
			(net "JTAG_BMC_PLD_TDO")
		)
	)
)
